(kicad_pcb
	(version 20260206)
	(generator "pcbnew")
	(generator_version "10.0")
	(general
		(thickness 1.6)
		(legacy_teardrops no)
	)
	(paper "A4")
	(title_block
		(title "04192023_DAF0TMB3IC0_F0TG_MB_C_brd_V02_OCP.brd")
		(comment 1 "Grand Teton / footprints 4329-4334 of 8354")
	)
	(layers
		(0 "F.Cu" signal "TOP")
		(4 "In1.Cu" signal "GND")
		(6 "In2.Cu" signal "IN1")
		(8 "In3.Cu" signal "GND1")
		(10 "In4.Cu" signal "IN2")
		(12 "In5.Cu" signal "GND2")
		(14 "In6.Cu" signal "IN3")
		(16 "In7.Cu" signal "GND3")
		(18 "In8.Cu" signal "VCC")
		(20 "In9.Cu" signal "VCC1")
		(22 "In10.Cu" signal "GND4")
		(24 "In11.Cu" signal "IN4")
		(26 "In12.Cu" signal "GND5")
		(28 "In13.Cu" signal "IN5")
		(30 "In14.Cu" signal "GND6")
		(32 "In15.Cu" signal "IN6")
		(34 "In16.Cu" signal "GND7")
		(2 "B.Cu" signal "BOTTOM")
		(9 "F.Adhes" user "F.Adhesive")
		(11 "B.Adhes" user "B.Adhesive")
		(13 "F.Paste" user "Package Geometry/Pastemask Top")
		(15 "B.Paste" user "Package Geometry/Pastemask Bottom")
		(5 "F.SilkS" user "Ref Des/Silkscreen Top")
		(7 "B.SilkS" user "Ref Des/Silkscreen Bottom")
		(1 "F.Mask" user "Board Geometry/Soldermask Top")
		(3 "B.Mask" user "Board Geometry/Soldermask Bottom")
		(17 "Dwgs.User" user "User.Drawings")
		(19 "Cmts.User" user "User.Comments")
		(21 "Eco1.User" user "User.Eco1")
		(23 "Eco2.User" user "User.Eco2")
		(25 "Edge.Cuts" user "Board Geometry/Outline")
		(27 "Margin" user)
		(31 "F.CrtYd" user "Package Geometry/Place Bound Top")
		(29 "B.CrtYd" user "Package Geometry/Place Bound Bottom")
		(35 "F.Fab" user "Ref Des/Assembly Top")
		(33 "B.Fab" user "Ref Des/Assembly Bottom")
	)
	(footprint ""
		(layer "F.Cu")
		(at 316.821058 -118.910608)
		(property "Reference" "C629"
			(at 0 0 0)
			(layer "F.SilkS")
			(hide yes)
			(effects
				(font
					(size 1.27 1.27)
				)
			)
		)
		(property "Value" ""
			(at 0 0 0)
			(layer "F.Fab")
			(effects
				(font
					(size 1.27 1.27)
				)
			)
		)
		(duplicate_pad_numbers_are_jumpers no)
		(fp_line
			(start -0.7874 -0.4064)
			(end 0.7874 -0.4064)
			(stroke
				(width 0.1524)
				(type default)
			)
			(layer "F.SilkS")
		)
		(fp_line
			(start -0.7874 0.4064)
			(end -0.7874 -0.4064)
			(stroke
				(width 0.1524)
				(type default)
			)
			(layer "F.SilkS")
		)
		(fp_line
			(start 0.7874 -0.4064)
			(end 0.7874 0.4064)
			(stroke
				(width 0.1524)
				(type default)
			)
			(layer "F.SilkS")
		)
		(fp_line
			(start 0.7874 0.4064)
			(end -0.7874 0.4064)
			(stroke
				(width 0.1524)
				(type default)
			)
			(layer "F.SilkS")
		)
		(fp_line
			(start -0.67945 -0.305054)
			(end -0.12065 -0.305054)
			(stroke
				(width 0.1)
				(type default)
			)
			(layer "F.Fab")
		)
		(fp_line
			(start -0.67945 0.3048)
			(end -0.67945 -0.305054)
			(stroke
				(width 0.1)
				(type default)
			)
			(layer "F.Fab")
		)
		(fp_line
			(start -0.12065 -0.305054)
			(end -0.12065 -0.2794)
			(stroke
				(width 0.1)
				(type default)
			)
			(layer "F.Fab")
		)
		(fp_line
			(start -0.12065 -0.2794)
			(end 0.12065 -0.2794)
			(stroke
				(width 0.1)
				(type default)
			)
			(layer "F.Fab")
		)
		(fp_line
			(start -0.12065 0.2794)
			(end -0.12065 0.3048)
			(stroke
				(width 0.1)
				(type default)
			)
			(layer "F.Fab")
		)
		(fp_line
			(start -0.12065 0.3048)
			(end -0.67945 0.3048)
			(stroke
				(width 0.1)
				(type default)
			)
			(layer "F.Fab")
		)
		(fp_line
			(start 0.120396 0.2794)
			(end -0.12065 0.2794)
			(stroke
				(width 0.1)
				(type default)
			)
			(layer "F.Fab")
		)
		(fp_line
			(start 0.120396 0.3048)
			(end 0.120396 0.2794)
			(stroke
				(width 0.1)
				(type default)
			)
			(layer "F.Fab")
		)
		(fp_line
			(start 0.12065 -0.3048)
			(end 0.67945 -0.3048)
			(stroke
				(width 0.1)
				(type default)
			)
			(layer "F.Fab")
		)
		(fp_line
			(start 0.12065 -0.2794)
			(end 0.12065 -0.3048)
			(stroke
				(width 0.1)
				(type default)
			)
			(layer "F.Fab")
		)
		(fp_line
			(start 0.67945 -0.3048)
			(end 0.67945 0.3048)
			(stroke
				(width 0.1)
				(type default)
			)
			(layer "F.Fab")
		)
		(fp_line
			(start 0.67945 0.3048)
			(end 0.120396 0.3048)
			(stroke
				(width 0.1)
				(type default)
			)
			(layer "F.Fab")
		)
		(pad "1" smd circle
			(at -0.40005 0)
			(size 0 0)
			(layers "F.Cu" "F.Mask" "F.Paste")
			(net "P3V3_AUX")
		)
		(pad "2" smd circle
			(at 0.40005 0)
			(size 0 0)
			(layers "F.Cu" "F.Mask" "F.Paste")
			(net "GND")
		)
	)
	(footprint ""
		(layer "F.Cu")
		(at 325.095108 -103.30815)
		(property "Reference" "U52"
			(at -1.63449 -4.200144 0)
			(unlocked yes)
			(layer "F.SilkS")
			(effects
				(font
					(size 0.7874 0.5842)
					(thickness 0.1524)
				)
			)
		)
		(property "Value" ""
			(at 0 0 0)
			(layer "F.Fab")
			(effects
				(font
					(size 1.27 1.27)
				)
			)
		)
		(duplicate_pad_numbers_are_jumpers no)
		(fp_line
			(start -1.500124 -1.500124)
			(end -1.004062 -1.500124)
			(stroke
				(width 0.1524)
				(type default)
			)
			(layer "F.SilkS")
		)
		(fp_line
			(start -1.500124 -1.004062)
			(end -1.500124 -1.500124)
			(stroke
				(width 0.1524)
				(type default)
			)
			(layer "F.SilkS")
		)
		(fp_line
			(start -1.500124 1.500124)
			(end -1.500124 1.004062)
			(stroke
				(width 0.1524)
				(type default)
			)
			(layer "F.SilkS")
		)
		(fp_line
			(start -1.004062 1.500124)
			(end -1.500124 1.500124)
			(stroke
				(width 0.1524)
				(type default)
			)
			(layer "F.SilkS")
		)
		(fp_line
			(start 1.004062 -1.500124)
			(end 1.500124 -1.500124)
			(stroke
				(width 0.1524)
				(type default)
			)
			(layer "F.SilkS")
		)
		(fp_line
			(start 1.500124 -1.500124)
			(end 1.500124 -1.004062)
			(stroke
				(width 0.1524)
				(type default)
			)
			(layer "F.SilkS")
		)
		(fp_line
			(start 1.500124 1.004062)
			(end 1.500124 1.500124)
			(stroke
				(width 0.1524)
				(type default)
			)
			(layer "F.SilkS")
		)
		(fp_line
			(start 1.500124 1.500124)
			(end 1.004062 1.500124)
			(stroke
				(width 0.1524)
				(type default)
			)
			(layer "F.SilkS")
		)
		(fp_poly
			(pts
				(xy -2.413 -2.50698) (xy -3.089402 -1.74879) (xy -1.992884 -1.45161)
			)
			(stroke
				(width 0)
				(type default)
			)
			(fill yes)
			(layer "F.SilkS")
		)
		(fp_line
			(start -1.500124 -1.500124)
			(end 1.500124 -1.500124)
			(stroke
				(width 0.1)
				(type default)
			)
			(layer "F.Fab")
		)
		(fp_line
			(start -1.500124 1.500124)
			(end -1.500124 -1.500124)
			(stroke
				(width 0.1)
				(type default)
			)
			(layer "F.Fab")
		)
		(fp_line
			(start 1.500124 -1.500124)
			(end 1.500124 1.500124)
			(stroke
				(width 0.1)
				(type default)
			)
			(layer "F.Fab")
		)
		(fp_line
			(start 1.500124 1.500124)
			(end -1.500124 1.500124)
			(stroke
				(width 0.1)
				(type default)
			)
			(layer "F.Fab")
		)
		(fp_poly
			(pts
				(xy -2.847848 -1.258062) (xy -2.847848 -0.242062) (xy -1.831848 -0.750062)
			)
			(stroke
				(width 0)
				(type default)
			)
			(fill yes)
			(layer "F.Fab")
		)
		(pad "1" smd rect
			(at -1.400048 -0.750062 270)
			(size 0.2286 0.6096)
			(layers "F.Cu" "F.Mask" "F.Paste")
			(net "INA230_8_A1")
		)
		(pad "2" smd rect
			(at -1.400048 -0.249936 270)
			(size 0.2286 0.6096)
			(layers "F.Cu" "F.Mask" "F.Paste")
			(net "INA230_8_A0")
		)
		(pad "3" smd rect
			(at -1.400048 0.249936 270)
			(size 0.2286 0.6096)
			(layers "F.Cu" "F.Mask" "F.Paste")
			(net "P12V_E1S_0_ADC_ALERT_R")
		)
		(pad "4" smd rect
			(at -1.400048 0.750062 270)
			(size 0.2286 0.6096)
			(layers "F.Cu" "F.Mask" "F.Paste")
			(net "SMB_INA230_8_3V3AUX_SDA_R1")
		)
		(pad "5" smd rect
			(at -0.750062 1.400048)
			(size 0.2286 0.6096)
			(layers "F.Cu" "F.Mask" "F.Paste")
			(net "SMB_INA230_8_3V3AUX_SCL_R1")
		)
		(pad "6" smd rect
			(at -0.249936 1.400048)
			(size 0.2286 0.6096)
			(layers "F.Cu" "F.Mask" "F.Paste")
			(net "NC_INA230_8_NC0")
		)
		(pad "7" smd rect
			(at 0.249936 1.400048)
			(size 0.2286 0.6096)
			(layers "F.Cu" "F.Mask" "F.Paste")
			(net "NC_INA230_8_NC1")
		)
		(pad "8" smd rect
			(at 0.750062 1.400048)
			(size 0.2286 0.6096)
			(layers "F.Cu" "F.Mask" "F.Paste")
			(net "NC_INA230_8_NC2")
		)
		(pad "9" smd rect
			(at 1.400048 0.750062 270)
			(size 0.2286 0.6096)
			(layers "F.Cu" "F.Mask" "F.Paste")
			(net "P3V3_AUX")
		)
		(pad "10" smd rect
			(at 1.400048 0.249936 270)
			(size 0.2286 0.6096)
			(layers "F.Cu" "F.Mask" "F.Paste")
			(net "GND")
		)
		(pad "11" smd rect
			(at 1.400048 -0.249936 270)
			(size 0.2286 0.6096)
			(layers "F.Cu" "F.Mask" "F.Paste")
			(net "P12V_E1S_0")
		)
		(pad "12" smd rect
			(at 1.400048 -0.750062 270)
			(size 0.2286 0.6096)
			(layers "F.Cu" "F.Mask" "F.Paste")
			(net "VSENSE_P12V_INA230_8_INN")
		)
		(pad "13" smd rect
			(at 0.750062 -1.400048)
			(size 0.2286 0.6096)
			(layers "F.Cu" "F.Mask" "F.Paste")
			(net "VSENSE_P12V_INA230_8_INP")
		)
		(pad "14" smd rect
			(at 0.249936 -1.400048)
			(size 0.2286 0.6096)
			(layers "F.Cu" "F.Mask" "F.Paste")
			(net "NC_INA230_8_NC3")
		)
		(pad "15" smd rect
			(at -0.249936 -1.400048)
			(size 0.2286 0.6096)
			(layers "F.Cu" "F.Mask" "F.Paste")
			(net "NC_INA230_8_NC4")
		)
		(pad "16" smd rect
			(at -0.750062 -1.400048)
			(size 0.2286 0.6096)
			(layers "F.Cu" "F.Mask" "F.Paste")
			(net "NC_INA230_8_NC5")
		)
		(pad "TH" smd rect
			(at 0 0)
			(size 1.7018 1.7018)
			(layers "F.Cu" "F.Mask" "F.Paste")
			(net "GND")
		)
		(zone
			(layer "F.Cu")
			(hatch none 0.5)
			(connect_pads
				(clearance 0)
			)
			(min_thickness 0.25)
			(keepout
				(tracks not_allowed)
				(vias allowed)
				(pads allowed)
				(copperpour not_allowed)
				(footprints allowed)
			)
			(placement
				(enabled no)
				(sheetname "")
			)
			(fill
				(thermal_gap 0.5)
				(thermal_bridge_width 0.5)
				(island_removal_mode 0)
			)
			(polygon
				(pts
					(xy 324.05066 -103.33355) (xy 324.05066 -104.352598) (xy 326.139556 -104.352598) (xy 326.139556 -102.263702)
					(xy 324.05066 -102.263702) (xy 324.05066 -103.30815) (xy 324.193408 -103.30815) (xy 324.193408 -102.40645)
					(xy 325.996808 -102.40645) (xy 325.996808 -104.20985) (xy 324.193408 -104.20985) (xy 324.193408 -103.33355)
				)
			)
		)
	)
	(footprint ""
		(layer "F.Cu")
		(at 28.53563 -422.330626 180)
		(property "Reference" "C1871"
			(at 0 0 180)
			(layer "F.SilkS")
			(hide yes)
			(effects
				(font
					(size 1.27 1.27)
				)
			)
		)
		(property "Value" ""
			(at 0 0 180)
			(layer "F.Fab")
			(effects
				(font
					(size 1.27 1.27)
				)
			)
		)
		(duplicate_pad_numbers_are_jumpers no)
		(fp_line
			(start 0.7874 0.4064)
			(end -0.7874 0.4064)
			(stroke
				(width 0.1524)
				(type default)
			)
			(layer "F.SilkS")
		)
		(fp_line
			(start 0.7874 -0.284226)
			(end 0.7874 0.4064)
			(stroke
				(width 0.1524)
				(type default)
			)
			(layer "F.SilkS")
		)
		(fp_line
			(start -0.7874 -0.4064)
			(end -0.34417 -0.4064)
			(stroke
				(width 0.1524)
				(type default)
			)
			(layer "F.SilkS")
		)
		(fp_line
			(start 0.6858 0.3048)
			(end 0.1016 0.3048)
			(stroke
				(width 0.1)
				(type default)
			)
			(layer "F.Fab")
		)
		(fp_line
			(start 0.6858 -0.3048)
			(end 0.6858 0.3048)
			(stroke
				(width 0.1)
				(type default)
			)
			(layer "F.Fab")
		)
		(fp_line
			(start 0.1016 0.3048)
			(end 0.1016 0.2794)
			(stroke
				(width 0.1)
				(type default)
			)
			(layer "F.Fab")
		)
		(fp_line
			(start 0.1016 0.2794)
			(end -0.1016 0.2794)
			(stroke
				(width 0.1)
				(type default)
			)
			(layer "F.Fab")
		)
		(fp_line
			(start 0.1016 -0.2794)
			(end 0.1016 -0.3048)
			(stroke
				(width 0.1)
				(type default)
			)
			(layer "F.Fab")
		)
		(fp_line
			(start 0.1016 -0.3048)
			(end 0.6858 -0.3048)
			(stroke
				(width 0.1)
				(type default)
			)
			(layer "F.Fab")
		)
		(fp_line
			(start -0.1016 0.3048)
			(end -0.6858 0.3048)
			(stroke
				(width 0.1)
				(type default)
			)
			(layer "F.Fab")
		)
		(fp_line
			(start -0.1016 0.2794)
			(end -0.1016 0.3048)
			(stroke
				(width 0.1)
				(type default)
			)
			(layer "F.Fab")
		)
		(fp_line
			(start -0.1016 -0.2794)
			(end 0.1016 -0.2794)
			(stroke
				(width 0.1)
				(type default)
			)
			(layer "F.Fab")
		)
		(fp_line
			(start -0.1016 -0.3048)
			(end -0.1016 -0.2794)
			(stroke
				(width 0.1)
				(type default)
			)
			(layer "F.Fab")
		)
		(fp_line
			(start -0.6858 0.3048)
			(end -0.6858 -0.3048)
			(stroke
				(width 0.1)
				(type default)
			)
			(layer "F.Fab")
		)
		(fp_line
			(start -0.6858 -0.3048)
			(end -0.1016 -0.3048)
			(stroke
				(width 0.1)
				(type default)
			)
			(layer "F.Fab")
		)
		(pad "1" smd rect
			(at -0.40005 0)
			(size 0.4572 0.508)
			(layers "F.Cu" "F.Mask" "F.Paste")
			(net "P2E_MB_BMC_TX_BUF_DN<0>")
		)
		(pad "2" smd rect
			(at 0.40005 0)
			(size 0.4572 0.508)
			(layers "F.Cu" "F.Mask" "F.Paste")
			(net "P2E_MB_BMC_TX_BUF_C_DN<0>")
		)
	)
	(footprint ""
		(layer "F.Cu")
		(at 177.81016 -393.2936)
		(property "Reference" "R1488"
			(at 0 0 0)
			(layer "F.SilkS")
			(hide yes)
			(effects
				(font
					(size 1.27 1.27)
				)
			)
		)
		(property "Value" ""
			(at 0 0 0)
			(layer "F.Fab")
			(effects
				(font
					(size 1.27 1.27)
				)
			)
		)
		(duplicate_pad_numbers_are_jumpers no)
		(fp_line
			(start -0.32512 -0.175006)
			(end 0.32512 -0.175006)
			(stroke
				(width 0.1)
				(type default)
			)
			(layer "F.Fab")
		)
		(fp_line
			(start -0.32512 0.175006)
			(end -0.32512 -0.175006)
			(stroke
				(width 0.1)
				(type default)
			)
			(layer "F.Fab")
		)
		(fp_line
			(start 0.32512 -0.175006)
			(end 0.32512 0.175006)
			(stroke
				(width 0.1)
				(type default)
			)
			(layer "F.Fab")
		)
		(fp_line
			(start 0.32512 0.175006)
			(end -0.32512 0.175006)
			(stroke
				(width 0.1)
				(type default)
			)
			(layer "F.Fab")
		)
		(pad "1" smd rect
			(at -0.2667 0)
			(size 0.3048 0.381)
			(layers "F.Cu" "F.Mask" "F.Paste")
			(net "P1V8_CPU1_RT_1D")
		)
		(pad "2" smd rect
			(at 0.2667 0 180)
			(size 0.3048 0.381)
			(layers "F.Cu" "F.Mask" "F.Paste")
			(net "JTAG_TDI_RT_CPU1_P2")
		)
	)
	(footprint ""
		(layer "F.Cu")
		(at 89.562432 -70.69582 -90)
		(property "Reference" "PR3855"
			(at 0 0 270)
			(layer "F.SilkS")
			(hide yes)
			(effects
				(font
					(size 1.27 1.27)
				)
			)
		)
		(property "Value" ""
			(at 0 0 270)
			(layer "F.Fab")
			(effects
				(font
					(size 1.27 1.27)
				)
			)
		)
		(duplicate_pad_numbers_are_jumpers no)
		(fp_line
			(start -0.7874 0.4064)
			(end -0.7874 -0.4064)
			(stroke
				(width 0.1524)
				(type default)
			)
			(layer "F.SilkS")
		)
		(fp_line
			(start 0.7874 0.4064)
			(end -0.7874 0.4064)
			(stroke
				(width 0.1524)
				(type default)
			)
			(layer "F.SilkS")
		)
		(fp_line
			(start -0.7874 -0.4064)
			(end 0.7874 -0.4064)
			(stroke
				(width 0.1524)
				(type default)
			)
			(layer "F.SilkS")
		)
		(fp_line
			(start 0.7874 -0.4064)
			(end 0.7874 0.4064)
			(stroke
				(width 0.1524)
				(type default)
			)
			(layer "F.SilkS")
		)
		(fp_line
			(start -0.67945 0.3048)
			(end -0.67945 -0.305054)
			(stroke
				(width 0.1)
				(type default)
			)
			(layer "F.Fab")
		)
		(fp_line
			(start -0.12065 0.3048)
			(end -0.67945 0.3048)
			(stroke
				(width 0.1)
				(type default)
			)
			(layer "F.Fab")
		)
		(fp_line
			(start 0.120396 0.3048)
			(end 0.120396 0.2794)
			(stroke
				(width 0.1)
				(type default)
			)
			(layer "F.Fab")
		)
		(fp_line
			(start 0.67945 0.3048)
			(end 0.120396 0.3048)
			(stroke
				(width 0.1)
				(type default)
			)
			(layer "F.Fab")
		)
		(fp_line
			(start -0.12065 0.2794)
			(end -0.12065 0.3048)
			(stroke
				(width 0.1)
				(type default)
			)
			(layer "F.Fab")
		)
		(fp_line
			(start 0.120396 0.2794)
			(end -0.12065 0.2794)
			(stroke
				(width 0.1)
				(type default)
			)
			(layer "F.Fab")
		)
		(fp_line
			(start -0.12065 -0.2794)
			(end 0.12065 -0.2794)
			(stroke
				(width 0.1)
				(type default)
			)
			(layer "F.Fab")
		)
		(fp_line
			(start 0.12065 -0.2794)
			(end 0.12065 -0.3048)
			(stroke
				(width 0.1)
				(type default)
			)
			(layer "F.Fab")
		)
		(fp_line
			(start 0.12065 -0.3048)
			(end 0.67945 -0.3048)
			(stroke
				(width 0.1)
				(type default)
			)
			(layer "F.Fab")
		)
		(fp_line
			(start 0.67945 -0.3048)
			(end 0.67945 0.3048)
			(stroke
				(width 0.1)
				(type default)
			)
			(layer "F.Fab")
		)
		(fp_line
			(start -0.67945 -0.305054)
			(end -0.12065 -0.305054)
			(stroke
				(width 0.1)
				(type default)
			)
			(layer "F.Fab")
		)
		(fp_line
			(start -0.12065 -0.305054)
			(end -0.12065 -0.2794)
			(stroke
				(width 0.1)
				(type default)
			)
			(layer "F.Fab")
		)
		(pad "1" smd circle
			(at -0.40005 0 270)
			(size 0 0)
			(layers "F.Cu" "F.Mask" "F.Paste")
			(net "P3V3_OCP_MODE_2")
		)
		(pad "2" smd circle
			(at 0.40005 0 270)
			(size 0 0)
			(layers "F.Cu" "F.Mask" "F.Paste")
			(net "GND")
		)
	)
	(footprint ""
		(layer "F.Cu")
		(at 226.0981 -400.972782 180)
		(property "Reference" "PR3987"
			(at 0 0 180)
			(layer "F.SilkS")
			(hide yes)
			(effects
				(font
					(size 1.27 1.27)
				)
			)
		)
		(property "Value" ""
			(at 0 0 180)
			(layer "F.Fab")
			(effects
				(font
					(size 1.27 1.27)
				)
			)
		)
		(duplicate_pad_numbers_are_jumpers no)
		(fp_line
			(start 0.7874 0.4064)
			(end -0.7874 0.4064)
			(stroke
				(width 0.1524)
				(type default)
			)
			(layer "F.SilkS")
		)
		(fp_line
			(start 0.7874 -0.4064)
			(end 0.7874 0.4064)
			(stroke
				(width 0.1524)
				(type default)
			)
			(layer "F.SilkS")
		)
		(fp_line
			(start -0.7874 0.4064)
			(end -0.7874 -0.4064)
			(stroke
				(width 0.1524)
				(type default)
			)
			(layer "F.SilkS")
		)
		(fp_line
			(start -0.7874 -0.4064)
			(end 0.7874 -0.4064)
			(stroke
				(width 0.1524)
				(type default)
			)
			(layer "F.SilkS")
		)
		(fp_line
			(start 0.67945 0.3048)
			(end 0.120396 0.3048)
			(stroke
				(width 0.1)
				(type default)
			)
			(layer "F.Fab")
		)
		(fp_line
			(start 0.67945 -0.3048)
			(end 0.67945 0.3048)
			(stroke
				(width 0.1)
				(type default)
			)
			(layer "F.Fab")
		)
		(fp_line
			(start 0.12065 -0.2794)
			(end 0.12065 -0.3048)
			(stroke
				(width 0.1)
				(type default)
			)
			(layer "F.Fab")
		)
		(fp_line
			(start 0.12065 -0.3048)
			(end 0.67945 -0.3048)
			(stroke
				(width 0.1)
				(type default)
			)
			(layer "F.Fab")
		)
		(fp_line
			(start 0.120396 0.3048)
			(end 0.120396 0.2794)
			(stroke
				(width 0.1)
				(type default)
			)
			(layer "F.Fab")
		)
		(fp_line
			(start 0.120396 0.2794)
			(end -0.12065 0.2794)
			(stroke
				(width 0.1)
				(type default)
			)
			(layer "F.Fab")
		)
		(fp_line
			(start -0.12065 0.3048)
			(end -0.67945 0.3048)
			(stroke
				(width 0.1)
				(type default)
			)
			(layer "F.Fab")
		)
		(fp_line
			(start -0.12065 0.2794)
			(end -0.12065 0.3048)
			(stroke
				(width 0.1)
				(type default)
			)
			(layer "F.Fab")
		)
		(fp_line
			(start -0.12065 -0.2794)
			(end 0.12065 -0.2794)
			(stroke
				(width 0.1)
				(type default)
			)
			(layer "F.Fab")
		)
		(fp_line
			(start -0.12065 -0.305054)
			(end -0.12065 -0.2794)
			(stroke
				(width 0.1)
				(type default)
			)
			(layer "F.Fab")
		)
		(fp_line
			(start -0.67945 0.3048)
			(end -0.67945 -0.305054)
			(stroke
				(width 0.1)
				(type default)
			)
			(layer "F.Fab")
		)
		(fp_line
			(start -0.67945 -0.305054)
			(end -0.12065 -0.305054)
			(stroke
				(width 0.1)
				(type default)
			)
			(layer "F.Fab")
		)
		(pad "1" smd circle
			(at -0.40005 0 180)
			(size 0 0)
			(layers "F.Cu" "F.Mask" "F.Paste")
			(net "HSC_CS_4")
		)
		(pad "2" smd circle
			(at 0.40005 0 180)
			(size 0 0)
			(layers "F.Cu" "F.Mask" "F.Paste")
			(net "AGND_HSC")
		)
	)
)
